(kicad_pcb
	(version 20260206)
	(generator "pcbnew")
	(generator_version "10.0")
	(general
		(thickness 1.6)
		(legacy_teardrops no)
	)
	(paper "A4")
	(title_block
		(title "01162023_DA0F0TEBIF0_F0T_Expander_BD_F_brd_V02_OCP.brd")
		(comment 1 "Grand Teton / footprints 8449-8455 of 9728")
	)
	(layers
		(0 "F.Cu" signal "TOP")
		(4 "In1.Cu" signal "GND")
		(6 "In2.Cu" signal "VCC")
		(8 "In3.Cu" signal "VCC1")
		(10 "In4.Cu" signal "GND1")
		(12 "In5.Cu" signal "IN1")
		(14 "In6.Cu" signal "GND2")
		(16 "In7.Cu" signal "IN2")
		(18 "In8.Cu" signal "GND3")
		(20 "In9.Cu" signal "IN3")
		(22 "In10.Cu" signal "GND4")
		(24 "In11.Cu" signal "IN4")
		(26 "In12.Cu" signal "GND5")
		(28 "In13.Cu" signal "IN5")
		(30 "In14.Cu" signal "GND6")
		(32 "In15.Cu" signal "IN6")
		(34 "In16.Cu" signal "GND7")
		(2 "B.Cu" signal "BOTTOM")
		(9 "F.Adhes" user "F.Adhesive")
		(11 "B.Adhes" user "B.Adhesive")
		(13 "F.Paste" user "Package Geometry/Pastemask Top")
		(15 "B.Paste" user "Package Geometry/Pastemask Bottom")
		(5 "F.SilkS" user "Ref Des/Silkscreen Top")
		(7 "B.SilkS" user "Ref Des/Silkscreen Bottom")
		(1 "F.Mask" user "Board Geometry/Soldermask Top")
		(3 "B.Mask" user "Board Geometry/Soldermask Bottom")
		(17 "Dwgs.User" user "User.Drawings")
		(19 "Cmts.User" user "User.Comments")
		(21 "Eco1.User" user "User.Eco1")
		(23 "Eco2.User" user "User.Eco2")
		(25 "Edge.Cuts" user "Board Geometry/Outline")
		(27 "Margin" user)
		(31 "F.CrtYd" user "Package Geometry/Place Bound Top")
		(29 "B.CrtYd" user "Package Geometry/Place Bound Bottom")
		(35 "F.Fab" user "Ref Des/Assembly Top")
		(33 "B.Fab" user "Ref Des/Assembly Bottom")
	)
	(footprint ""
		(layer "B.Cu")
		(at 351.197418 -207.739234 -90)
		(property "Reference" "R5774"
			(at 0 0 90)
			(layer "B.SilkS")
			(hide yes)
			(effects
				(font
					(size 1.27 1.27)
				)
				(justify mirror)
			)
		)
		(property "Value" ""
			(at 0 0 90)
			(layer "B.Fab")
			(effects
				(font
					(size 1.27 1.27)
				)
				(justify mirror)
			)
		)
		(duplicate_pad_numbers_are_jumpers no)
		(fp_line
			(start -0.7874 0.4064)
			(end 0.7874 0.4064)
			(stroke
				(width 0.1524)
				(type default)
			)
			(layer "B.SilkS")
		)
		(fp_line
			(start 0.7874 0.4064)
			(end 0.7874 -0.4064)
			(stroke
				(width 0.1524)
				(type default)
			)
			(layer "B.SilkS")
		)
		(fp_line
			(start -0.7874 -0.4064)
			(end -0.7874 0.4064)
			(stroke
				(width 0.1524)
				(type default)
			)
			(layer "B.SilkS")
		)
		(fp_line
			(start 0.7874 -0.4064)
			(end -0.7874 -0.4064)
			(stroke
				(width 0.1524)
				(type default)
			)
			(layer "B.SilkS")
		)
		(fp_line
			(start -0.67945 0.3048)
			(end -0.120396 0.3048)
			(stroke
				(width 0.1)
				(type default)
			)
			(layer "B.Fab")
		)
		(fp_line
			(start -0.120396 0.3048)
			(end -0.120396 0.2794)
			(stroke
				(width 0.1)
				(type default)
			)
			(layer "B.Fab")
		)
		(fp_line
			(start 0.12065 0.3048)
			(end 0.67945 0.3048)
			(stroke
				(width 0.1)
				(type default)
			)
			(layer "B.Fab")
		)
		(fp_line
			(start 0.67945 0.3048)
			(end 0.67945 -0.305054)
			(stroke
				(width 0.1)
				(type default)
			)
			(layer "B.Fab")
		)
		(fp_line
			(start -0.120396 0.2794)
			(end 0.12065 0.2794)
			(stroke
				(width 0.1)
				(type default)
			)
			(layer "B.Fab")
		)
		(fp_line
			(start 0.12065 0.2794)
			(end 0.12065 0.3048)
			(stroke
				(width 0.1)
				(type default)
			)
			(layer "B.Fab")
		)
		(fp_line
			(start -0.12065 -0.2794)
			(end -0.12065 -0.3048)
			(stroke
				(width 0.1)
				(type default)
			)
			(layer "B.Fab")
		)
		(fp_line
			(start 0.12065 -0.2794)
			(end -0.12065 -0.2794)
			(stroke
				(width 0.1)
				(type default)
			)
			(layer "B.Fab")
		)
		(fp_line
			(start -0.67945 -0.3048)
			(end -0.67945 0.3048)
			(stroke
				(width 0.1)
				(type default)
			)
			(layer "B.Fab")
		)
		(fp_line
			(start -0.12065 -0.3048)
			(end -0.67945 -0.3048)
			(stroke
				(width 0.1)
				(type default)
			)
			(layer "B.Fab")
		)
		(fp_line
			(start 0.12065 -0.305054)
			(end 0.12065 -0.2794)
			(stroke
				(width 0.1)
				(type default)
			)
			(layer "B.Fab")
		)
		(fp_line
			(start 0.67945 -0.305054)
			(end 0.12065 -0.305054)
			(stroke
				(width 0.1)
				(type default)
			)
			(layer "B.Fab")
		)
		(pad "1" smd circle
			(at 0.40005 0 90)
			(size 0 0)
			(layers "B.Cu" "B.Mask" "B.Paste")
			(net "RST_FT4232_R_N")
		)
		(pad "2" smd circle
			(at -0.40005 0 90)
			(size 0 0)
			(layers "B.Cu" "B.Mask" "B.Paste")
			(net "RST_FT4232_N")
		)
	)
	(footprint ""
		(layer "B.Cu")
		(at 98.292412 -351.719388 180)
		(property "Reference" "R6374"
			(at 0 0 0)
			(layer "B.SilkS")
			(hide yes)
			(effects
				(font
					(size 1.27 1.27)
				)
				(justify mirror)
			)
		)
		(property "Value" ""
			(at 0 0 0)
			(layer "B.Fab")
			(effects
				(font
					(size 1.27 1.27)
				)
				(justify mirror)
			)
		)
		(duplicate_pad_numbers_are_jumpers no)
		(fp_line
			(start 0.7874 0.4064)
			(end 0.7874 -0.4064)
			(stroke
				(width 0.1524)
				(type default)
			)
			(layer "B.SilkS")
		)
		(fp_line
			(start 0.7874 -0.4064)
			(end -0.7874 -0.4064)
			(stroke
				(width 0.1524)
				(type default)
			)
			(layer "B.SilkS")
		)
		(fp_line
			(start -0.7874 0.4064)
			(end 0.7874 0.4064)
			(stroke
				(width 0.1524)
				(type default)
			)
			(layer "B.SilkS")
		)
		(fp_line
			(start -0.7874 -0.4064)
			(end -0.7874 0.4064)
			(stroke
				(width 0.1524)
				(type default)
			)
			(layer "B.SilkS")
		)
		(fp_line
			(start 0.67945 0.3048)
			(end 0.67945 -0.305054)
			(stroke
				(width 0.1)
				(type default)
			)
			(layer "B.Fab")
		)
		(fp_line
			(start 0.67945 -0.305054)
			(end 0.12065 -0.305054)
			(stroke
				(width 0.1)
				(type default)
			)
			(layer "B.Fab")
		)
		(fp_line
			(start 0.12065 0.3048)
			(end 0.67945 0.3048)
			(stroke
				(width 0.1)
				(type default)
			)
			(layer "B.Fab")
		)
		(fp_line
			(start 0.12065 0.2794)
			(end 0.12065 0.3048)
			(stroke
				(width 0.1)
				(type default)
			)
			(layer "B.Fab")
		)
		(fp_line
			(start 0.12065 -0.2794)
			(end -0.12065 -0.2794)
			(stroke
				(width 0.1)
				(type default)
			)
			(layer "B.Fab")
		)
		(fp_line
			(start 0.12065 -0.305054)
			(end 0.12065 -0.2794)
			(stroke
				(width 0.1)
				(type default)
			)
			(layer "B.Fab")
		)
		(fp_line
			(start -0.120396 0.3048)
			(end -0.120396 0.2794)
			(stroke
				(width 0.1)
				(type default)
			)
			(layer "B.Fab")
		)
		(fp_line
			(start -0.120396 0.2794)
			(end 0.12065 0.2794)
			(stroke
				(width 0.1)
				(type default)
			)
			(layer "B.Fab")
		)
		(fp_line
			(start -0.12065 -0.2794)
			(end -0.12065 -0.3048)
			(stroke
				(width 0.1)
				(type default)
			)
			(layer "B.Fab")
		)
		(fp_line
			(start -0.12065 -0.3048)
			(end -0.67945 -0.3048)
			(stroke
				(width 0.1)
				(type default)
			)
			(layer "B.Fab")
		)
		(fp_line
			(start -0.67945 0.3048)
			(end -0.120396 0.3048)
			(stroke
				(width 0.1)
				(type default)
			)
			(layer "B.Fab")
		)
		(fp_line
			(start -0.67945 -0.3048)
			(end -0.67945 0.3048)
			(stroke
				(width 0.1)
				(type default)
			)
			(layer "B.Fab")
		)
		(pad "1" smd circle
			(at 0.40005 0)
			(size 0 0)
			(layers "B.Cu" "B.Mask" "B.Paste")
			(net "CLK_100M_DB800ZL_PEX0_S3_R_DP")
		)
		(pad "2" smd circle
			(at -0.40005 0)
			(size 0 0)
			(layers "B.Cu" "B.Mask" "B.Paste")
			(net "CLK_100M_DB800ZL_PEX0_S3_DP")
		)
	)
	(footprint ""
		(layer "B.Cu")
		(at 228.553264 -208.78546 90)
		(property "Reference" "R5295"
			(at 0 0 90)
			(layer "B.SilkS")
			(hide yes)
			(effects
				(font
					(size 1.27 1.27)
				)
				(justify mirror)
			)
		)
		(property "Value" ""
			(at 0 0 90)
			(layer "B.Fab")
			(effects
				(font
					(size 1.27 1.27)
				)
				(justify mirror)
			)
		)
		(duplicate_pad_numbers_are_jumpers no)
		(fp_line
			(start 0.7874 -0.4064)
			(end -0.7874 -0.4064)
			(stroke
				(width 0.1524)
				(type default)
			)
			(layer "B.SilkS")
		)
		(fp_line
			(start -0.7874 -0.4064)
			(end -0.7874 0.4064)
			(stroke
				(width 0.1524)
				(type default)
			)
			(layer "B.SilkS")
		)
		(fp_line
			(start 0.7874 0.4064)
			(end 0.7874 -0.4064)
			(stroke
				(width 0.1524)
				(type default)
			)
			(layer "B.SilkS")
		)
		(fp_line
			(start -0.7874 0.4064)
			(end 0.7874 0.4064)
			(stroke
				(width 0.1524)
				(type default)
			)
			(layer "B.SilkS")
		)
		(fp_line
			(start 0.67945 -0.305054)
			(end 0.12065 -0.305054)
			(stroke
				(width 0.1)
				(type default)
			)
			(layer "B.Fab")
		)
		(fp_line
			(start 0.12065 -0.305054)
			(end 0.12065 -0.2794)
			(stroke
				(width 0.1)
				(type default)
			)
			(layer "B.Fab")
		)
		(fp_line
			(start -0.12065 -0.3048)
			(end -0.67945 -0.3048)
			(stroke
				(width 0.1)
				(type default)
			)
			(layer "B.Fab")
		)
		(fp_line
			(start -0.67945 -0.3048)
			(end -0.67945 0.3048)
			(stroke
				(width 0.1)
				(type default)
			)
			(layer "B.Fab")
		)
		(fp_line
			(start 0.12065 -0.2794)
			(end -0.12065 -0.2794)
			(stroke
				(width 0.1)
				(type default)
			)
			(layer "B.Fab")
		)
		(fp_line
			(start -0.12065 -0.2794)
			(end -0.12065 -0.3048)
			(stroke
				(width 0.1)
				(type default)
			)
			(layer "B.Fab")
		)
		(fp_line
			(start 0.12065 0.2794)
			(end 0.12065 0.3048)
			(stroke
				(width 0.1)
				(type default)
			)
			(layer "B.Fab")
		)
		(fp_line
			(start -0.120396 0.2794)
			(end 0.12065 0.2794)
			(stroke
				(width 0.1)
				(type default)
			)
			(layer "B.Fab")
		)
		(fp_line
			(start 0.67945 0.3048)
			(end 0.67945 -0.305054)
			(stroke
				(width 0.1)
				(type default)
			)
			(layer "B.Fab")
		)
		(fp_line
			(start 0.12065 0.3048)
			(end 0.67945 0.3048)
			(stroke
				(width 0.1)
				(type default)
			)
			(layer "B.Fab")
		)
		(fp_line
			(start -0.120396 0.3048)
			(end -0.120396 0.2794)
			(stroke
				(width 0.1)
				(type default)
			)
			(layer "B.Fab")
		)
		(fp_line
			(start -0.67945 0.3048)
			(end -0.120396 0.3048)
			(stroke
				(width 0.1)
				(type default)
			)
			(layer "B.Fab")
		)
		(pad "1" smd circle
			(at 0.40005 0 270)
			(size 0 0)
			(layers "B.Cu" "B.Mask" "B.Paste")
			(net "BIC_SEL_FLASH_SW2")
		)
		(pad "2" smd circle
			(at -0.40005 0 270)
			(size 0 0)
			(layers "B.Cu" "B.Mask" "B.Paste")
			(net "BIC_SEL_FLASH_SW2_R")
		)
	)
	(footprint ""
		(layer "B.Cu")
		(at 287.06445 -195.290186)
		(property "Reference" "R6658"
			(at 0 0 0)
			(layer "B.SilkS")
			(hide yes)
			(effects
				(font
					(size 1.27 1.27)
				)
				(justify mirror)
			)
		)
		(property "Value" ""
			(at 0 0 0)
			(layer "B.Fab")
			(effects
				(font
					(size 1.27 1.27)
				)
				(justify mirror)
			)
		)
		(duplicate_pad_numbers_are_jumpers no)
		(fp_line
			(start -0.7874 -0.4064)
			(end -0.7874 0.4064)
			(stroke
				(width 0.1524)
				(type default)
			)
			(layer "B.SilkS")
		)
		(fp_line
			(start -0.7874 0.4064)
			(end 0.7874 0.4064)
			(stroke
				(width 0.1524)
				(type default)
			)
			(layer "B.SilkS")
		)
		(fp_line
			(start 0.7874 -0.4064)
			(end -0.7874 -0.4064)
			(stroke
				(width 0.1524)
				(type default)
			)
			(layer "B.SilkS")
		)
		(fp_line
			(start 0.7874 0.4064)
			(end 0.7874 -0.4064)
			(stroke
				(width 0.1524)
				(type default)
			)
			(layer "B.SilkS")
		)
		(fp_line
			(start -0.67945 -0.3048)
			(end -0.67945 0.3048)
			(stroke
				(width 0.1)
				(type default)
			)
			(layer "B.Fab")
		)
		(fp_line
			(start -0.67945 0.3048)
			(end -0.120396 0.3048)
			(stroke
				(width 0.1)
				(type default)
			)
			(layer "B.Fab")
		)
		(fp_line
			(start -0.12065 -0.3048)
			(end -0.67945 -0.3048)
			(stroke
				(width 0.1)
				(type default)
			)
			(layer "B.Fab")
		)
		(fp_line
			(start -0.12065 -0.2794)
			(end -0.12065 -0.3048)
			(stroke
				(width 0.1)
				(type default)
			)
			(layer "B.Fab")
		)
		(fp_line
			(start -0.120396 0.2794)
			(end 0.12065 0.2794)
			(stroke
				(width 0.1)
				(type default)
			)
			(layer "B.Fab")
		)
		(fp_line
			(start -0.120396 0.3048)
			(end -0.120396 0.2794)
			(stroke
				(width 0.1)
				(type default)
			)
			(layer "B.Fab")
		)
		(fp_line
			(start 0.12065 -0.305054)
			(end 0.12065 -0.2794)
			(stroke
				(width 0.1)
				(type default)
			)
			(layer "B.Fab")
		)
		(fp_line
			(start 0.12065 -0.2794)
			(end -0.12065 -0.2794)
			(stroke
				(width 0.1)
				(type default)
			)
			(layer "B.Fab")
		)
		(fp_line
			(start 0.12065 0.2794)
			(end 0.12065 0.3048)
			(stroke
				(width 0.1)
				(type default)
			)
			(layer "B.Fab")
		)
		(fp_line
			(start 0.12065 0.3048)
			(end 0.67945 0.3048)
			(stroke
				(width 0.1)
				(type default)
			)
			(layer "B.Fab")
		)
		(fp_line
			(start 0.67945 -0.305054)
			(end 0.12065 -0.305054)
			(stroke
				(width 0.1)
				(type default)
			)
			(layer "B.Fab")
		)
		(fp_line
			(start 0.67945 0.3048)
			(end 0.67945 -0.305054)
			(stroke
				(width 0.1)
				(type default)
			)
			(layer "B.Fab")
		)
		(pad "1" smd circle
			(at 0.40005 0 180)
			(size 0 0)
			(layers "B.Cu" "B.Mask" "B.Paste")
			(net "SPI_BIC1_LS23_EN_N")
		)
		(pad "2" smd circle
			(at -0.40005 0 180)
			(size 0 0)
			(layers "B.Cu" "B.Mask" "B.Paste")
			(net "P1V8_PEX")
		)
	)
	(footprint ""
		(layer "B.Cu")
		(at 419.349936 -298.27474 180)
		(property "Reference" "C3465"
			(at 0 0 0)
			(layer "B.SilkS")
			(hide yes)
			(effects
				(font
					(size 1.27 1.27)
				)
				(justify mirror)
			)
		)
		(property "Value" ""
			(at 0 0 0)
			(layer "B.Fab")
			(effects
				(font
					(size 1.27 1.27)
				)
				(justify mirror)
			)
		)
		(duplicate_pad_numbers_are_jumpers no)
		(fp_line
			(start 0.299974 0.150114)
			(end 0.299974 -0.150114)
			(stroke
				(width 0.1)
				(type default)
			)
			(layer "B.Fab")
		)
		(fp_line
			(start 0.299974 -0.150114)
			(end -0.299974 -0.150114)
			(stroke
				(width 0.1)
				(type default)
			)
			(layer "B.Fab")
		)
		(fp_line
			(start -0.299974 0.150114)
			(end 0.299974 0.150114)
			(stroke
				(width 0.1)
				(type default)
			)
			(layer "B.Fab")
		)
		(fp_line
			(start -0.299974 -0.150114)
			(end -0.299974 0.150114)
			(stroke
				(width 0.1)
				(type default)
			)
			(layer "B.Fab")
		)
		(pad "1" smd rect
			(at 0.2667 0)
			(size 0.3048 0.381)
			(layers "B.Cu" "B.Mask" "B.Paste")
			(net "P1V25_PEX3")
		)
		(pad "2" smd rect
			(at -0.2667 0)
			(size 0.3048 0.381)
			(layers "B.Cu" "B.Mask" "B.Paste")
			(net "GND")
		)
	)
	(footprint ""
		(layer "B.Cu")
		(at 449.863718 -278.333962)
		(property "Reference" "C4402"
			(at 0 0 0)
			(layer "B.SilkS")
			(hide yes)
			(effects
				(font
					(size 1.27 1.27)
				)
				(justify mirror)
			)
		)
		(property "Value" ""
			(at 0 0 0)
			(layer "B.Fab")
			(effects
				(font
					(size 1.27 1.27)
				)
				(justify mirror)
			)
		)
		(duplicate_pad_numbers_are_jumpers no)
		(fp_line
			(start -1.2954 -0.5842)
			(end -1.2954 0.5842)
			(stroke
				(width 0.1524)
				(type default)
			)
			(layer "B.SilkS")
		)
		(fp_line
			(start -1.2954 0.5842)
			(end 1.2954 0.5842)
			(stroke
				(width 0.1524)
				(type default)
			)
			(layer "B.SilkS")
		)
		(fp_line
			(start 1.2954 -0.5842)
			(end -1.2954 -0.5842)
			(stroke
				(width 0.1524)
				(type default)
			)
			(layer "B.SilkS")
		)
		(fp_line
			(start 1.2954 0.5842)
			(end 1.2954 -0.5842)
			(stroke
				(width 0.1524)
				(type default)
			)
			(layer "B.SilkS")
		)
		(fp_line
			(start -1.1938 -0.4064)
			(end -1.1938 0.4064)
			(stroke
				(width 0.1)
				(type default)
			)
			(layer "B.Fab")
		)
		(fp_line
			(start -1.1938 0.4064)
			(end -0.8636 0.4064)
			(stroke
				(width 0.1)
				(type default)
			)
			(layer "B.Fab")
		)
		(fp_line
			(start -0.8636 -0.4572)
			(end -0.8636 -0.4064)
			(stroke
				(width 0.1)
				(type default)
			)
			(layer "B.Fab")
		)
		(fp_line
			(start -0.8636 -0.4064)
			(end -1.1938 -0.4064)
			(stroke
				(width 0.1)
				(type default)
			)
			(layer "B.Fab")
		)
		(fp_line
			(start -0.8636 0.4064)
			(end -0.8636 0.4572)
			(stroke
				(width 0.1)
				(type default)
			)
			(layer "B.Fab")
		)
		(fp_line
			(start -0.8636 0.4572)
			(end 0.8636 0.4572)
			(stroke
				(width 0.1)
				(type default)
			)
			(layer "B.Fab")
		)
		(fp_line
			(start 0.8636 -0.4572)
			(end -0.8636 -0.4572)
			(stroke
				(width 0.1)
				(type default)
			)
			(layer "B.Fab")
		)
		(fp_line
			(start 0.8636 -0.4064)
			(end 0.8636 -0.4572)
			(stroke
				(width 0.1)
				(type default)
			)
			(layer "B.Fab")
		)
		(fp_line
			(start 0.8636 0.4064)
			(end 1.1938 0.4064)
			(stroke
				(width 0.1)
				(type default)
			)
			(layer "B.Fab")
		)
		(fp_line
			(start 0.8636 0.4572)
			(end 0.8636 0.4064)
			(stroke
				(width 0.1)
				(type default)
			)
			(layer "B.Fab")
		)
		(fp_line
			(start 1.1938 -0.4064)
			(end 0.8636 -0.4064)
			(stroke
				(width 0.1)
				(type default)
			)
			(layer "B.Fab")
		)
		(fp_line
			(start 1.1938 0.4064)
			(end 1.1938 -0.4064)
			(stroke
				(width 0.1)
				(type default)
			)
			(layer "B.Fab")
		)
		(pad "1" smd rect
			(at 0.7366 0 270)
			(size 0.7112 0.8128)
			(layers "B.Cu" "B.Mask" "B.Paste")
			(net "P1V25_PEX3")
		)
		(pad "2" smd rect
			(at -0.7366 0 270)
			(size 0.7112 0.8128)
			(layers "B.Cu" "B.Mask" "B.Paste")
			(net "GND")
		)
	)
	(footprint ""
		(layer "B.Cu")
		(at 4.893818 -288.21507)
		(property "Reference" "PC986"
			(at 0 0 0)
			(layer "B.SilkS")
			(hide yes)
			(effects
				(font
					(size 1.27 1.27)
				)
				(justify mirror)
			)
		)
		(property "Value" ""
			(at 0 0 0)
			(layer "B.Fab")
			(effects
				(font
					(size 1.27 1.27)
				)
				(justify mirror)
			)
		)
		(duplicate_pad_numbers_are_jumpers no)
		(fp_line
			(start -1.524 -0.762)
			(end -1.524 0.762)
			(stroke
				(width 0.1524)
				(type default)
			)
			(layer "B.SilkS")
		)
		(fp_line
			(start -1.524 0.762)
			(end 1.524 0.762)
			(stroke
				(width 0.1524)
				(type default)
			)
			(layer "B.SilkS")
		)
		(fp_line
			(start 1.524 -0.762)
			(end -1.524 -0.762)
			(stroke
				(width 0.1524)
				(type default)
			)
			(layer "B.SilkS")
		)
		(fp_line
			(start 1.524 0.762)
			(end 1.524 -0.762)
			(stroke
				(width 0.1524)
				(type default)
			)
			(layer "B.SilkS")
		)
		(fp_line
			(start -1.1049 -0.724916)
			(end 1.1049 -0.724916)
			(stroke
				(width 0.1)
				(type default)
			)
			(layer "B.Fab")
		)
		(fp_line
			(start -1.1049 0.724916)
			(end -1.1049 -0.724916)
			(stroke
				(width 0.1)
				(type default)
			)
			(layer "B.Fab")
		)
		(fp_line
			(start 1.1049 -0.724916)
			(end 1.1049 0.724916)
			(stroke
				(width 0.1)
				(type default)
			)
			(layer "B.Fab")
		)
		(fp_line
			(start 1.1049 0.724916)
			(end -1.1049 0.724916)
			(stroke
				(width 0.1)
				(type default)
			)
			(layer "B.Fab")
		)
		(pad "1" smd rect
			(at 0.889 0)
			(size 1.016 1.27)
			(layers "B.Cu" "B.Mask" "B.Paste")
			(net "P1V25_PEX0_R")
		)
		(pad "2" smd rect
			(at -0.889 0)
			(size 1.016 1.27)
			(layers "B.Cu" "B.Mask" "B.Paste")
			(net "GND")
		)
	)
)
